# T6G (Grand Teton) — schematic netlist excerpt (pin names and nets, part order shuffled) for the footprints in the layout excerpt that follows; sources: Cadence DE-HDL packaged netlist, KiCad conversion of 04192023_DAF0TMB3IC0_F0TG_MB_C_brd_V02_OCP.brd

R9003  Q_RES  100K 1% EMPTY  pkg 0402LF  page 123 : A = PRSNT_CABLE_SWB_B1_N ; B = GND
PC425_5  Q_CAP  0.1UF 25V 10% X7R  pkg 0402  page 220 : A = SW_P12V_AUX_PVDDCR_CPU1_P1_FLT ; B = GND

(kicad_pcb
	(version 20260206)
	(generator "pcbnew")
	(generator_version "10.0")
	(general
		(thickness 1.6)
		(legacy_teardrops no)
	)
	(paper "A4")
	(title_block
		(title "04192023_DAF0TMB3IC0_F0TG_MB_C_brd_V02_OCP.brd")
		(comment 1 "Grand Teton / footprints 1508-1509 of 8354")
	)
	(layers
		(0 "F.Cu" signal "TOP")
		(4 "In1.Cu" signal "GND")
		(6 "In2.Cu" signal "IN1")
		(8 "In3.Cu" signal "GND1")
		(10 "In4.Cu" signal "IN2")
		(12 "In5.Cu" signal "GND2")
		(14 "In6.Cu" signal "IN3")
		(16 "In7.Cu" signal "GND3")
		(18 "In8.Cu" signal "VCC")
		(20 "In9.Cu" signal "VCC1")
		(22 "In10.Cu" signal "GND4")
		(24 "In11.Cu" signal "IN4")
		(26 "In12.Cu" signal "GND5")
		(28 "In13.Cu" signal "IN5")
		(30 "In14.Cu" signal "GND6")
		(32 "In15.Cu" signal "IN6")
		(34 "In16.Cu" signal "GND7")
		(2 "B.Cu" signal "BOTTOM")
		(9 "F.Adhes" user "F.Adhesive")
		(11 "B.Adhes" user "B.Adhesive")
		(13 "F.Paste" user "Package Geometry/Pastemask Top")
		(15 "B.Paste" user "Package Geometry/Pastemask Bottom")
		(5 "F.SilkS" user "Ref Des/Silkscreen Top")
		(7 "B.SilkS" user "Ref Des/Silkscreen Bottom")
		(1 "F.Mask" user "Board Geometry/Soldermask Top")
		(3 "B.Mask" user "Board Geometry/Soldermask Bottom")
		(17 "Dwgs.User" user "User.Drawings")
		(19 "Cmts.User" user "User.Comments")
		(21 "Eco1.User" user "User.Eco1")
		(23 "Eco2.User" user "User.Eco2")
		(25 "Edge.Cuts" user "Board Geometry/Outline")
		(27 "Margin" user)
		(31 "F.CrtYd" user "Package Geometry/Place Bound Top")
		(29 "B.CrtYd" user "Package Geometry/Place Bound Bottom")
		(35 "F.Fab" user "Ref Des/Assembly Top")
		(33 "B.Fab" user "Ref Des/Assembly Bottom")
	)
	(footprint ""
		(layer "F.Cu")
		(at 362.025438 -412.334964 180)
		(property "Reference" "R9003"
			(at 0 0 180)
			(layer "F.SilkS")
			(hide yes)
			(effects
				(font
					(size 1.27 1.27)
				)
			)
		)
		(property "Value" ""
			(at 0 0 180)
			(layer "F.Fab")
			(effects
				(font
					(size 1.27 1.27)
				)
			)
		)
		(duplicate_pad_numbers_are_jumpers no)
		(fp_line
			(start 0.7874 0.4064)
			(end -0.7874 0.4064)
			(stroke
				(width 0.1524)
				(type default)
			)
			(layer "F.SilkS")
		)
		(fp_line
			(start 0.7874 -0.4064)
			(end 0.7874 0.4064)
			(stroke
				(width 0.1524)
				(type default)
			)
			(layer "F.SilkS")
		)
		(fp_line
			(start -0.7874 0.4064)
			(end -0.7874 -0.4064)
			(stroke
				(width 0.1524)
				(type default)
			)
			(layer "F.SilkS")
		)
		(fp_line
			(start -0.7874 -0.4064)
			(end 0.7874 -0.4064)
			(stroke
				(width 0.1524)
				(type default)
			)
			(layer "F.SilkS")
		)
		(fp_line
			(start 0.67945 0.3048)
			(end 0.120396 0.3048)
			(stroke
				(width 0.1)
				(type default)
			)
			(layer "F.Fab")
		)
		(fp_line
			(start 0.67945 -0.3048)
			(end 0.67945 0.3048)
			(stroke
				(width 0.1)
				(type default)
			)
			(layer "F.Fab")
		)
		(fp_line
			(start 0.12065 -0.2794)
			(end 0.12065 -0.3048)
			(stroke
				(width 0.1)
				(type default)
			)
			(layer "F.Fab")
		)
		(fp_line
			(start 0.12065 -0.3048)
			(end 0.67945 -0.3048)
			(stroke
				(width 0.1)
				(type default)
			)
			(layer "F.Fab")
		)
		(fp_line
			(start 0.120396 0.3048)
			(end 0.120396 0.2794)
			(stroke
				(width 0.1)
				(type default)
			)
			(layer "F.Fab")
		)
		(fp_line
			(start 0.120396 0.2794)
			(end -0.12065 0.2794)
			(stroke
				(width 0.1)
				(type default)
			)
			(layer "F.Fab")
		)
		(fp_line
			(start -0.12065 0.3048)
			(end -0.67945 0.3048)
			(stroke
				(width 0.1)
				(type default)
			)
			(layer "F.Fab")
		)
		(fp_line
			(start -0.12065 0.2794)
			(end -0.12065 0.3048)
			(stroke
				(width 0.1)
				(type default)
			)
			(layer "F.Fab")
		)
		(fp_line
			(start -0.12065 -0.2794)
			(end 0.12065 -0.2794)
			(stroke
				(width 0.1)
				(type default)
			)
			(layer "F.Fab")
		)
		(fp_line
			(start -0.12065 -0.305054)
			(end -0.12065 -0.2794)
			(stroke
				(width 0.1)
				(type default)
			)
			(layer "F.Fab")
		)
		(fp_line
			(start -0.67945 0.3048)
			(end -0.67945 -0.305054)
			(stroke
				(width 0.1)
				(type default)
			)
			(layer "F.Fab")
		)
		(fp_line
			(start -0.67945 -0.305054)
			(end -0.12065 -0.305054)
			(stroke
				(width 0.1)
				(type default)
			)
			(layer "F.Fab")
		)
		(pad "1" smd circle
			(at -0.40005 0 180)
			(size 0 0)
			(layers "F.Cu" "F.Mask" "F.Paste")
			(net "PRSNT_CABLE_SWB_B1_N")
		)
		(pad "2" smd circle
			(at 0.40005 0 180)
			(size 0 0)
			(layers "F.Cu" "F.Mask" "F.Paste")
			(net "GND")
		)
	)
	(footprint ""
		(layer "F.Cu")
		(at 91.317318 -339.413596)
		(property "Reference" "PC425_5"
			(at 0 0 0)
			(layer "F.SilkS")
			(hide yes)
			(effects
				(font
					(size 1.27 1.27)
				)
			)
		)
		(property "Value" ""
			(at 0 0 0)
			(layer "F.Fab")
			(effects
				(font
					(size 1.27 1.27)
				)
			)
		)
		(duplicate_pad_numbers_are_jumpers no)
		(fp_line
			(start -0.7874 -0.4064)
			(end 0.7874 -0.4064)
			(stroke
				(width 0.1524)
				(type default)
			)
			(layer "F.SilkS")
		)
		(fp_line
			(start -0.7874 0.4064)
			(end -0.7874 -0.4064)
			(stroke
				(width 0.1524)
				(type default)
			)
			(layer "F.SilkS")
		)
		(fp_line
			(start 0.7874 -0.4064)
			(end 0.7874 0.4064)
			(stroke
				(width 0.1524)
				(type default)
			)
			(layer "F.SilkS")
		)
		(fp_line
			(start 0.7874 0.4064)
			(end -0.7874 0.4064)
			(stroke
				(width 0.1524)
				(type default)
			)
			(layer "F.SilkS")
		)
		(fp_line
			(start -0.67945 -0.305054)
			(end -0.12065 -0.305054)
			(stroke
				(width 0.1)
				(type default)
			)
			(layer "F.Fab")
		)
		(fp_line
			(start -0.67945 0.3048)
			(end -0.67945 -0.305054)
			(stroke
				(width 0.1)
				(type default)
			)
			(layer "F.Fab")
		)
		(fp_line
			(start -0.12065 -0.305054)
			(end -0.12065 -0.2794)
			(stroke
				(width 0.1)
				(type default)
			)
			(layer "F.Fab")
		)
		(fp_line
			(start -0.12065 -0.2794)
			(end 0.12065 -0.2794)
			(stroke
				(width 0.1)
				(type default)
			)
			(layer "F.Fab")
		)
		(fp_line
			(start -0.12065 0.2794)
			(end -0.12065 0.3048)
			(stroke
				(width 0.1)
				(type default)
			)
			(layer "F.Fab")
		)
		(fp_line
			(start -0.12065 0.3048)
			(end -0.67945 0.3048)
			(stroke
				(width 0.1)
				(type default)
			)
			(layer "F.Fab")
		)
		(fp_line
			(start 0.120396 0.2794)
			(end -0.12065 0.2794)
			(stroke
				(width 0.1)
				(type default)
			)
			(layer "F.Fab")
		)
		(fp_line
			(start 0.120396 0.3048)
			(end 0.120396 0.2794)
			(stroke
				(width 0.1)
				(type default)
			)
			(layer "F.Fab")
		)
		(fp_line
			(start 0.12065 -0.3048)
			(end 0.67945 -0.3048)
			(stroke
				(width 0.1)
				(type default)
			)
			(layer "F.Fab")
		)
		(fp_line
			(start 0.12065 -0.2794)
			(end 0.12065 -0.3048)
			(stroke
				(width 0.1)
				(type default)
			)
			(layer "F.Fab")
		)
		(fp_line
			(start 0.67945 -0.3048)
			(end 0.67945 0.3048)
			(stroke
				(width 0.1)
				(type default)
			)
			(layer "F.Fab")
		)
		(fp_line
			(start 0.67945 0.3048)
			(end 0.120396 0.3048)
			(stroke
				(width 0.1)
				(type default)
			)
			(layer "F.Fab")
		)
		(pad "1" smd circle
			(at -0.40005 0)
			(size 0 0)
			(layers "F.Cu" "F.Mask" "F.Paste")
			(net "SW_P12V_AUX_PVDDCR_CPU1_P1_FLT")
		)
		(pad "2" smd circle
			(at 0.40005 0)
			(size 0 0)
			(layers "F.Cu" "F.Mask" "F.Paste")
			(net "GND")
		)
	)
)
